# T6G (Grand Teton) — schematic netlist excerpt (pin names and nets, part order shuffled) for the footprints in the layout excerpt that follows; sources: Cadence DE-HDL packaged netlist, KiCad conversion of 04192023_DAF0TMB3IC0_F0TG_MB_C_brd_V02_OCP.brd

PC22  Q_CAP  1UF 25V 10% X6S  pkg C0402  page 226 : A = SW_P12V_AUX_PVDD18_S5_P1_FLT ; B = GND
R930  Q_RES  0 5% CHIP  pkg 0402LF  page 54 : A = CPU1_XTRIG_L5 ; B = CPU1_XTRIG_R1_L5

(kicad_pcb
	(version 20260206)
	(generator "pcbnew")
	(generator_version "10.0")
	(general
		(thickness 1.6)
		(legacy_teardrops no)
	)
	(paper "A4")
	(title_block
		(title "04192023_DAF0TMB3IC0_F0TG_MB_C_brd_V02_OCP.brd")
		(comment 1 "Grand Teton / footprints 2892-2893 of 8354")
	)
	(layers
		(0 "F.Cu" signal "TOP")
		(4 "In1.Cu" signal "GND")
		(6 "In2.Cu" signal "IN1")
		(8 "In3.Cu" signal "GND1")
		(10 "In4.Cu" signal "IN2")
		(12 "In5.Cu" signal "GND2")
		(14 "In6.Cu" signal "IN3")
		(16 "In7.Cu" signal "GND3")
		(18 "In8.Cu" signal "VCC")
		(20 "In9.Cu" signal "VCC1")
		(22 "In10.Cu" signal "GND4")
		(24 "In11.Cu" signal "IN4")
		(26 "In12.Cu" signal "GND5")
		(28 "In13.Cu" signal "IN5")
		(30 "In14.Cu" signal "GND6")
		(32 "In15.Cu" signal "IN6")
		(34 "In16.Cu" signal "GND7")
		(2 "B.Cu" signal "BOTTOM")
		(9 "F.Adhes" user "F.Adhesive")
		(11 "B.Adhes" user "B.Adhesive")
		(13 "F.Paste" user "Package Geometry/Pastemask Top")
		(15 "B.Paste" user "Package Geometry/Pastemask Bottom")
		(5 "F.SilkS" user "Ref Des/Silkscreen Top")
		(7 "B.SilkS" user "Ref Des/Silkscreen Bottom")
		(1 "F.Mask" user "Board Geometry/Soldermask Top")
		(3 "B.Mask" user "Board Geometry/Soldermask Bottom")
		(17 "Dwgs.User" user "User.Drawings")
		(19 "Cmts.User" user "User.Comments")
		(21 "Eco1.User" user "User.Eco1")
		(23 "Eco2.User" user "User.Eco2")
		(25 "Edge.Cuts" user "Board Geometry/Outline")
		(27 "Margin" user)
		(31 "F.CrtYd" user "Package Geometry/Place Bound Top")
		(29 "B.CrtYd" user "Package Geometry/Place Bound Bottom")
		(35 "F.Fab" user "Ref Des/Assembly Top")
		(33 "B.Fab" user "Ref Des/Assembly Bottom")
	)
	(footprint ""
		(layer "F.Cu")
		(at 66.666364 -151.549862 -90)
		(property "Reference" "PC22"
			(at 0 0 270)
			(layer "F.SilkS")
			(hide yes)
			(effects
				(font
					(size 1.27 1.27)
				)
			)
		)
		(property "Value" ""
			(at 0 0 270)
			(layer "F.Fab")
			(effects
				(font
					(size 1.27 1.27)
				)
			)
		)
		(duplicate_pad_numbers_are_jumpers no)
		(fp_line
			(start -0.7874 0.4064)
			(end -0.7874 -0.4064)
			(stroke
				(width 0.1524)
				(type default)
			)
			(layer "F.SilkS")
		)
		(fp_line
			(start 0.7874 0.4064)
			(end -0.7874 0.4064)
			(stroke
				(width 0.1524)
				(type default)
			)
			(layer "F.SilkS")
		)
		(fp_line
			(start -0.7874 -0.4064)
			(end 0.7874 -0.4064)
			(stroke
				(width 0.1524)
				(type default)
			)
			(layer "F.SilkS")
		)
		(fp_line
			(start 0.7874 -0.4064)
			(end 0.7874 0.4064)
			(stroke
				(width 0.1524)
				(type default)
			)
			(layer "F.SilkS")
		)
		(fp_line
			(start -0.67945 0.3048)
			(end -0.67945 -0.305054)
			(stroke
				(width 0.1)
				(type default)
			)
			(layer "F.Fab")
		)
		(fp_line
			(start -0.12065 0.3048)
			(end -0.67945 0.3048)
			(stroke
				(width 0.1)
				(type default)
			)
			(layer "F.Fab")
		)
		(fp_line
			(start 0.120396 0.3048)
			(end 0.120396 0.2794)
			(stroke
				(width 0.1)
				(type default)
			)
			(layer "F.Fab")
		)
		(fp_line
			(start 0.67945 0.3048)
			(end 0.120396 0.3048)
			(stroke
				(width 0.1)
				(type default)
			)
			(layer "F.Fab")
		)
		(fp_line
			(start -0.12065 0.2794)
			(end -0.12065 0.3048)
			(stroke
				(width 0.1)
				(type default)
			)
			(layer "F.Fab")
		)
		(fp_line
			(start 0.120396 0.2794)
			(end -0.12065 0.2794)
			(stroke
				(width 0.1)
				(type default)
			)
			(layer "F.Fab")
		)
		(fp_line
			(start -0.12065 -0.2794)
			(end 0.12065 -0.2794)
			(stroke
				(width 0.1)
				(type default)
			)
			(layer "F.Fab")
		)
		(fp_line
			(start 0.12065 -0.2794)
			(end 0.12065 -0.3048)
			(stroke
				(width 0.1)
				(type default)
			)
			(layer "F.Fab")
		)
		(fp_line
			(start 0.12065 -0.3048)
			(end 0.67945 -0.3048)
			(stroke
				(width 0.1)
				(type default)
			)
			(layer "F.Fab")
		)
		(fp_line
			(start 0.67945 -0.3048)
			(end 0.67945 0.3048)
			(stroke
				(width 0.1)
				(type default)
			)
			(layer "F.Fab")
		)
		(fp_line
			(start -0.67945 -0.305054)
			(end -0.12065 -0.305054)
			(stroke
				(width 0.1)
				(type default)
			)
			(layer "F.Fab")
		)
		(fp_line
			(start -0.12065 -0.305054)
			(end -0.12065 -0.2794)
			(stroke
				(width 0.1)
				(type default)
			)
			(layer "F.Fab")
		)
		(pad "1" smd circle
			(at -0.40005 0 270)
			(size 0 0)
			(layers "F.Cu" "F.Mask" "F.Paste")
			(net "SW_P12V_AUX_PVDD18_S5_P1_FLT")
		)
		(pad "2" smd circle
			(at 0.40005 0 270)
			(size 0 0)
			(layers "F.Cu" "F.Mask" "F.Paste")
			(net "GND")
		)
	)
	(footprint ""
		(layer "F.Cu")
		(at 2.677922 -58.875168 -90)
		(property "Reference" "R930"
			(at 0 0 270)
			(layer "F.SilkS")
			(hide yes)
			(effects
				(font
					(size 1.27 1.27)
				)
			)
		)
		(property "Value" ""
			(at 0 0 270)
			(layer "F.Fab")
			(effects
				(font
					(size 1.27 1.27)
				)
			)
		)
		(duplicate_pad_numbers_are_jumpers no)
		(fp_line
			(start -0.7874 0.4064)
			(end -0.7874 -0.4064)
			(stroke
				(width 0.1524)
				(type default)
			)
			(layer "F.SilkS")
		)
		(fp_line
			(start 0.7874 0.4064)
			(end -0.7874 0.4064)
			(stroke
				(width 0.1524)
				(type default)
			)
			(layer "F.SilkS")
		)
		(fp_line
			(start -0.7874 -0.4064)
			(end 0.7874 -0.4064)
			(stroke
				(width 0.1524)
				(type default)
			)
			(layer "F.SilkS")
		)
		(fp_line
			(start 0.7874 -0.4064)
			(end 0.7874 0.4064)
			(stroke
				(width 0.1524)
				(type default)
			)
			(layer "F.SilkS")
		)
		(fp_line
			(start -0.67945 0.3048)
			(end -0.67945 -0.305054)
			(stroke
				(width 0.1)
				(type default)
			)
			(layer "F.Fab")
		)
		(fp_line
			(start -0.12065 0.3048)
			(end -0.67945 0.3048)
			(stroke
				(width 0.1)
				(type default)
			)
			(layer "F.Fab")
		)
		(fp_line
			(start 0.120396 0.3048)
			(end 0.120396 0.2794)
			(stroke
				(width 0.1)
				(type default)
			)
			(layer "F.Fab")
		)
		(fp_line
			(start 0.67945 0.3048)
			(end 0.120396 0.3048)
			(stroke
				(width 0.1)
				(type default)
			)
			(layer "F.Fab")
		)
		(fp_line
			(start -0.12065 0.2794)
			(end -0.12065 0.3048)
			(stroke
				(width 0.1)
				(type default)
			)
			(layer "F.Fab")
		)
		(fp_line
			(start 0.120396 0.2794)
			(end -0.12065 0.2794)
			(stroke
				(width 0.1)
				(type default)
			)
			(layer "F.Fab")
		)
		(fp_line
			(start -0.12065 -0.2794)
			(end 0.12065 -0.2794)
			(stroke
				(width 0.1)
				(type default)
			)
			(layer "F.Fab")
		)
		(fp_line
			(start 0.12065 -0.2794)
			(end 0.12065 -0.3048)
			(stroke
				(width 0.1)
				(type default)
			)
			(layer "F.Fab")
		)
		(fp_line
			(start 0.12065 -0.3048)
			(end 0.67945 -0.3048)
			(stroke
				(width 0.1)
				(type default)
			)
			(layer "F.Fab")
		)
		(fp_line
			(start 0.67945 -0.3048)
			(end 0.67945 0.3048)
			(stroke
				(width 0.1)
				(type default)
			)
			(layer "F.Fab")
		)
		(fp_line
			(start -0.67945 -0.305054)
			(end -0.12065 -0.305054)
			(stroke
				(width 0.1)
				(type default)
			)
			(layer "F.Fab")
		)
		(fp_line
			(start -0.12065 -0.305054)
			(end -0.12065 -0.2794)
			(stroke
				(width 0.1)
				(type default)
			)
			(layer "F.Fab")
		)
		(pad "1" smd circle
			(at -0.40005 0 270)
			(size 0 0)
			(layers "F.Cu" "F.Mask" "F.Paste")
			(net "CPU1_XTRIG_L5")
		)
		(pad "2" smd circle
			(at 0.40005 0 270)
			(size 0 0)
			(layers "F.Cu" "F.Mask" "F.Paste")
			(net "CPU1_XTRIG_R1_L5")
		)
	)
)
